(kicad_pcb
	(version 20260206)
	(generator "pcbnew")
	(generator_version "10.0")
	(general
		(thickness 1.6)
		(legacy_teardrops no)
	)
	(paper "A4")
	(title_block
		(title "12092022_DA0F0TFB6D0_F0T_FAN_BOARD_MP5048_D_brd_v02_OCP.brd")
		(comment 1 "Grand Teton / footprints 754-758 of 924")
	)
	(layers
		(0 "F.Cu" signal "TOP")
		(4 "In1.Cu" signal "GND")
		(6 "In2.Cu" signal "IN1")
		(8 "In3.Cu" signal "IN2")
		(10 "In4.Cu" signal "GND1")
		(2 "B.Cu" signal "BOTTOM")
		(9 "F.Adhes" user "F.Adhesive")
		(11 "B.Adhes" user "B.Adhesive")
		(13 "F.Paste" user "Package Geometry/Pastemask Top")
		(15 "B.Paste" user "Package Geometry/Pastemask Bottom")
		(5 "F.SilkS" user "Ref Des/Silkscreen Top")
		(7 "B.SilkS" user "Ref Des/Silkscreen Bottom")
		(1 "F.Mask" user "Board Geometry/Soldermask Top")
		(3 "B.Mask" user "Board Geometry/Soldermask Bottom")
		(17 "Dwgs.User" user "User.Drawings")
		(19 "Cmts.User" user "User.Comments")
		(21 "Eco1.User" user "User.Eco1")
		(23 "Eco2.User" user "User.Eco2")
		(25 "Edge.Cuts" user "Board Geometry/Outline")
		(27 "Margin" user)
		(31 "F.CrtYd" user "Package Geometry/Place Bound Top")
		(29 "B.CrtYd" user "Package Geometry/Place Bound Bottom")
		(35 "F.Fab" user "Ref Des/Assembly Top")
		(33 "B.Fab" user "Ref Des/Assembly Bottom")
	)
	(footprint ""
		(layer "B.Cu")
		(at 44.99991 -118.709948)
		(property "Reference" "J3"
			(at 4.53009 -5.215382 0)
			(unlocked yes)
			(layer "B.SilkS")
			(effects
				(font
					(size 0.7874 0.5842)
					(thickness 0.1524)
				)
				(justify left mirror)
			)
		)
		(property "Value" ""
			(at 0 0 0)
			(layer "B.Fab")
			(effects
				(font
					(size 1.27 1.27)
				)
				(justify mirror)
			)
		)
		(duplicate_pad_numbers_are_jumpers no)
		(fp_line
			(start -6.35 -4.52501)
			(end 4.350004 -4.52501)
			(stroke
				(width 0.1524)
				(type default)
			)
			(layer "B.SilkS")
		)
		(fp_line
			(start -6.35 18.524982)
			(end -6.35 -4.52501)
			(stroke
				(width 0.1524)
				(type default)
			)
			(layer "B.SilkS")
		)
		(fp_line
			(start -3.24993 -1.42494)
			(end -1.96977 -1.42494)
			(stroke
				(width 0.1524)
				(type default)
			)
			(layer "B.SilkS")
		)
		(fp_line
			(start -3.24993 15.424912)
			(end -3.24993 -1.42494)
			(stroke
				(width 0.1524)
				(type default)
			)
			(layer "B.SilkS")
		)
		(fp_line
			(start -0.029972 -1.42494)
			(end 1.249934 -1.42494)
			(stroke
				(width 0.1524)
				(type default)
			)
			(layer "B.SilkS")
		)
		(fp_line
			(start 1.249934 -1.42494)
			(end 1.249934 5.799836)
			(stroke
				(width 0.1524)
				(type default)
			)
			(layer "B.SilkS")
		)
		(fp_line
			(start 1.249934 5.799836)
			(end 4.350004 5.799836)
			(stroke
				(width 0.1524)
				(type default)
			)
			(layer "B.SilkS")
		)
		(fp_line
			(start 1.249934 8.200136)
			(end 1.249934 15.424912)
			(stroke
				(width 0.1524)
				(type default)
			)
			(layer "B.SilkS")
		)
		(fp_line
			(start 1.249934 8.200136)
			(end 4.350004 8.200136)
			(stroke
				(width 0.1524)
				(type default)
			)
			(layer "B.SilkS")
		)
		(fp_line
			(start 1.249934 15.424912)
			(end -3.24993 15.424912)
			(stroke
				(width 0.1524)
				(type default)
			)
			(layer "B.SilkS")
		)
		(fp_line
			(start 4.350004 -4.52501)
			(end 4.350004 18.524982)
			(stroke
				(width 0.1524)
				(type default)
			)
			(layer "B.SilkS")
		)
		(fp_line
			(start 4.350004 18.524982)
			(end -6.35 18.524982)
			(stroke
				(width 0.1524)
				(type default)
			)
			(layer "B.SilkS")
		)
		(fp_poly
			(pts
				(xy 5.527802 -0.508) (xy 5.527802 0.508) (xy 4.511802 0)
			)
			(stroke
				(width 0)
				(type default)
			)
			(fill yes)
			(layer "B.SilkS")
		)
		(fp_line
			(start -6.35 -4.52501)
			(end 4.350004 -4.52501)
			(stroke
				(width 0.1)
				(type default)
			)
			(layer "B.Fab")
		)
		(fp_line
			(start -6.35 18.524982)
			(end -6.35 -4.52501)
			(stroke
				(width 0.1)
				(type default)
			)
			(layer "B.Fab")
		)
		(fp_line
			(start 4.350004 -4.52501)
			(end 4.350004 18.524982)
			(stroke
				(width 0.1)
				(type default)
			)
			(layer "B.Fab")
		)
		(fp_line
			(start 4.350004 18.524982)
			(end -6.35 18.524982)
			(stroke
				(width 0.1)
				(type default)
			)
			(layer "B.Fab")
		)
		(fp_poly
			(pts
				(xy 5.527802 -0.508) (xy 5.527802 0.508) (xy 4.511802 0)
			)
			(stroke
				(width 0)
				(type default)
			)
			(fill yes)
			(layer "B.Fab")
		)
		(pad "" np_thru_hole circle
			(at -0.999998 -1.89992 270)
			(size 1.4986 1.4986)
			(drill 1.4986)
			(layers "*.Cu" "*.Mask")
			(clearance 0.381)
			(thermal_gap 0.381)
		)
		(pad "1" thru_hole rect
			(at 0 0 270)
			(size 1.3716 1.3716)
			(drill 0.9652)
			(layers "*.Cu" "*.Mask")
			(remove_unused_layers no)
			(net "FAN_2_TACH_IL_D")
			(clearance 0.0508)
			(padstack
				(mode front_inner_back)
				(layer "Inner"
					(shape circle)
					(size 1.3716 1.3716)
					(clearance 0.0508)
				)
				(layer "B.Cu"
					(shape rect)
					(size 1.3716 1.3716)
					(thermal_gap 0.0508)
					(clearance 0.0508)
				)
			)
		)
		(pad "2" thru_hole circle
			(at -1.999996 0 270)
			(size 1.3716 1.3716)
			(drill 0.9652)
			(layers "*.Cu" "*.Mask")
			(remove_unused_layers no)
			(net "FAN_2_PWM_OL_R")
			(clearance 0.0508)
			(thermal_gap 0.0508)
		)
		(pad "3" thru_hole circle
			(at 0 1.999996 270)
			(size 1.3716 1.3716)
			(drill 0.9652)
			(layers "*.Cu" "*.Mask")
			(remove_unused_layers no)
			(net "FAN_2_PWM_IL_R")
			(clearance 0.0508)
			(thermal_gap 0.0508)
		)
		(pad "4" thru_hole circle
			(at -1.999996 1.999996 270)
			(size 1.3716 1.3716)
			(drill 0.9652)
			(layers "*.Cu" "*.Mask")
			(remove_unused_layers no)
			(net "FAN_2_PRESENT_R_N")
			(clearance 0.0508)
			(thermal_gap 0.0508)
		)
		(pad "5" thru_hole circle
			(at 0 3.999992 270)
			(size 1.3716 1.3716)
			(drill 0.9652)
			(layers "*.Cu" "*.Mask")
			(remove_unused_layers no)
			(net "P12V_LED_R1_FAN2")
			(clearance 0.0508)
			(thermal_gap 0.0508)
		)
		(pad "6" thru_hole circle
			(at -1.999996 3.999992 270)
			(size 1.3716 1.3716)
			(drill 0.9652)
			(layers "*.Cu" "*.Mask")
			(remove_unused_layers no)
			(net "SMB_FAN2_SCL_R")
			(clearance 0.0508)
			(thermal_gap 0.0508)
		)
		(pad "7" thru_hole circle
			(at 0 5.999988 270)
			(size 1.3716 1.3716)
			(drill 0.9652)
			(layers "*.Cu" "*.Mask")
			(remove_unused_layers no)
			(net "SMB_FAN2_SDA_R")
			(clearance 0.0508)
			(thermal_gap 0.0508)
		)
		(pad "8" thru_hole circle
			(at -1.999996 5.999988 270)
			(size 1.3716 1.3716)
			(drill 0.9652)
			(layers "*.Cu" "*.Mask")
			(remove_unused_layers no)
			(net "GND")
			(clearance 0.0508)
			(thermal_gap 0.0508)
		)
		(pad "9" thru_hole circle
			(at 0 7.999984 270)
			(size 1.3716 1.3716)
			(drill 0.9652)
			(layers "*.Cu" "*.Mask")
			(remove_unused_layers no)
			(net "GND")
			(clearance 0.0508)
			(thermal_gap 0.0508)
		)
		(pad "10" thru_hole circle
			(at -1.999996 7.999984 270)
			(size 1.3716 1.3716)
			(drill 0.9652)
			(layers "*.Cu" "*.Mask")
			(remove_unused_layers no)
			(net "P52V_FAN_2")
			(clearance 0.0508)
			(thermal_gap 0.0508)
		)
		(pad "11" thru_hole circle
			(at 0 9.99998 270)
			(size 1.3716 1.3716)
			(drill 0.9652)
			(layers "*.Cu" "*.Mask")
			(remove_unused_layers no)
			(net "P52V_FAN_2")
			(clearance 0.0508)
			(thermal_gap 0.0508)
		)
		(pad "12" thru_hole circle
			(at -1.999996 9.99998 270)
			(size 1.3716 1.3716)
			(drill 0.9652)
			(layers "*.Cu" "*.Mask")
			(remove_unused_layers no)
			(net "FAN_2_FAIL_R_LED_N")
			(clearance 0.0508)
			(thermal_gap 0.0508)
		)
		(pad "13" thru_hole circle
			(at 0 11.999976 270)
			(size 1.3716 1.3716)
			(drill 0.9652)
			(layers "*.Cu" "*.Mask")
			(remove_unused_layers no)
			(net "FAN_2_TACH_OL_D")
			(clearance 0.0508)
			(thermal_gap 0.0508)
		)
		(pad "14" thru_hole circle
			(at -1.999996 11.999976 270)
			(size 1.3716 1.3716)
			(drill 0.9652)
			(layers "*.Cu" "*.Mask")
			(remove_unused_layers no)
			(net "FAN_2_OK_R_LED_N")
			(clearance 0.0508)
			(thermal_gap 0.0508)
		)
		(pad "15" thru_hole circle
			(at 0 13.999972 270)
			(size 1.3716 1.3716)
			(drill 0.9652)
			(layers "*.Cu" "*.Mask")
			(remove_unused_layers no)
			(net "Net_612")
			(clearance 0.0508)
			(thermal_gap 0.0508)
		)
		(pad "16" thru_hole circle
			(at -1.999996 13.999972 270)
			(size 1.3716 1.3716)
			(drill 0.9652)
			(layers "*.Cu" "*.Mask")
			(remove_unused_layers no)
			(net "Net_611")
			(clearance 0.0508)
			(thermal_gap 0.0508)
		)
		(zone
			(layers "F.Cu" "B.Cu" "In1.Cu" "In2.Cu" "In3.Cu" "In4.Cu")
			(hatch none 0.5)
			(connect_pads
				(clearance 0)
			)
			(min_thickness 0.25)
			(keepout
				(tracks not_allowed)
				(vias allowed)
				(pads allowed)
				(copperpour not_allowed)
				(footprints allowed)
			)
			(placement
				(enabled no)
				(sheetname "")
			)
			(fill
				(thermal_gap 0.5)
				(thermal_bridge_width 0.5)
				(island_removal_mode 0)
			)
			(polygon
				(pts
					(arc
						(start 45.257212 -120.609868)
						(mid 42.742612 -120.609868)
						(end 45.257212 -120.609868)
					)
				)
			)
		)
	)
	(footprint ""
		(layer "B.Cu")
		(at 33.142428 -263.017 -90)
		(property "Reference" "PD3"
			(at 4.699 3.832098 270)
			(unlocked yes)
			(layer "B.SilkS")
			(effects
				(font
					(size 0.7874 0.5842)
					(thickness 0.1524)
				)
				(justify left mirror)
			)
		)
		(property "Value" ""
			(at 0 0 90)
			(layer "B.Fab")
			(effects
				(font
					(size 1.27 1.27)
				)
				(justify mirror)
			)
		)
		(duplicate_pad_numbers_are_jumpers no)
		(fp_line
			(start -5.536184 3.109976)
			(end -5.536184 -3.109976)
			(stroke
				(width 0.1524)
				(type default)
			)
			(layer "B.SilkS")
		)
		(fp_line
			(start 4.647184 3.109976)
			(end -5.536184 3.109976)
			(stroke
				(width 0.1524)
				(type default)
			)
			(layer "B.SilkS")
		)
		(fp_line
			(start 0.635 0.635)
			(end -0.635 -0.127)
			(stroke
				(width 0.1524)
				(type default)
			)
			(layer "B.SilkS")
		)
		(fp_line
			(start -0.635 -0.127)
			(end -1.397 -0.127)
			(stroke
				(width 0.1524)
				(type default)
			)
			(layer "B.SilkS")
		)
		(fp_line
			(start -0.635 -0.127)
			(end 0.635 -0.889)
			(stroke
				(width 0.1524)
				(type default)
			)
			(layer "B.SilkS")
		)
		(fp_line
			(start 1.397 -0.127)
			(end 0.635 -0.127)
			(stroke
				(width 0.1524)
				(type default)
			)
			(layer "B.SilkS")
		)
		(fp_line
			(start 0.635 -0.889)
			(end 0.635 0.635)
			(stroke
				(width 0.1524)
				(type default)
			)
			(layer "B.SilkS")
		)
		(fp_line
			(start -0.762 -1.143)
			(end -0.762 0.889)
			(stroke
				(width 0.1524)
				(type default)
			)
			(layer "B.SilkS")
		)
		(fp_line
			(start -5.536184 -3.109976)
			(end 4.647184 -3.109976)
			(stroke
				(width 0.1524)
				(type default)
			)
			(layer "B.SilkS")
		)
		(fp_line
			(start 4.647184 -3.109976)
			(end 4.647184 3.109976)
			(stroke
				(width 0.1524)
				(type default)
			)
			(layer "B.SilkS")
		)
		(fp_poly
			(pts
				(xy -5.5118 -3.0988) (xy -5.5118 3.1496) (xy -4.572 3.1496) (xy -4.572 -3.0988)
			)
			(stroke
				(width 0)
				(type default)
			)
			(fill yes)
			(layer "B.SilkS")
		)
		(fp_line
			(start -3.554984 3.109976)
			(end -3.554984 -3.109976)
			(stroke
				(width 0.1)
				(type default)
			)
			(layer "B.Fab")
		)
		(fp_line
			(start 3.554984 3.109976)
			(end -3.554984 3.109976)
			(stroke
				(width 0.1)
				(type default)
			)
			(layer "B.Fab")
		)
		(fp_line
			(start -3.554984 -3.109976)
			(end 3.554984 -3.109976)
			(stroke
				(width 0.1)
				(type default)
			)
			(layer "B.Fab")
		)
		(fp_line
			(start 3.554984 -3.109976)
			(end 3.554984 3.109976)
			(stroke
				(width 0.1)
				(type default)
			)
			(layer "B.Fab")
		)
		(fp_text user "+"
			(at 6.096 1.805178 270)
			(unlocked yes)
			(layer "B.SilkS")
			(effects
				(font
					(size 1.905 1.4224)
					(thickness 0.1524)
				)
				(justify left mirror)
			)
		)
		(fp_text user "-"
			(at -5.334 -0.34925 270)
			(unlocked yes)
			(layer "B.SilkS")
			(effects
				(font
					(size 1.905 1.4224)
					(thickness 0.1524)
				)
				(justify left mirror)
			)
		)
		(fp_text user "+"
			(at 6.1214 -0.32385 270)
			(unlocked yes)
			(layer "B.Fab")
			(effects
				(font
					(size 1.905 1.4224)
					(thickness 0.1524)
				)
				(justify left mirror)
			)
		)
		(fp_text user "-"
			(at -5.334 -0.34925 270)
			(unlocked yes)
			(layer "B.Fab")
			(effects
				(font
					(size 1.905 1.4224)
					(thickness 0.1524)
				)
				(justify left mirror)
			)
		)
		(pad "A" smd rect
			(at 3.299968 0 90)
			(size 2.413 3.302)
			(layers "B.Cu" "B.Mask" "B.Paste")
			(net "GND")
		)
		(pad "C" smd rect
			(at -3.299968 0 90)
			(size 2.413 3.302)
			(layers "B.Cu" "B.Mask" "B.Paste")
			(net "P52V_HSC")
		)
	)
	(footprint ""
		(layer "B.Cu")
		(at 16.782796 -274.764754 180)
		(property "Reference" "C2119"
			(at 0 0 0)
			(layer "B.SilkS")
			(hide yes)
			(effects
				(font
					(size 1.27 1.27)
				)
				(justify mirror)
			)
		)
		(property "Value" ""
			(at 0 0 0)
			(layer "B.Fab")
			(effects
				(font
					(size 1.27 1.27)
				)
				(justify mirror)
			)
		)
		(duplicate_pad_numbers_are_jumpers no)
		(fp_line
			(start 2.2098 0.9398)
			(end 2.2098 -0.9398)
			(stroke
				(width 0.1524)
				(type default)
			)
			(layer "B.SilkS")
		)
		(fp_line
			(start 2.2098 -0.9398)
			(end -2.2098 -0.9398)
			(stroke
				(width 0.1524)
				(type default)
			)
			(layer "B.SilkS")
		)
		(fp_line
			(start -2.2098 0.9398)
			(end 2.2098 0.9398)
			(stroke
				(width 0.1524)
				(type default)
			)
			(layer "B.SilkS")
		)
		(fp_line
			(start -2.2098 -0.9398)
			(end -2.2098 0.9398)
			(stroke
				(width 0.1524)
				(type default)
			)
			(layer "B.SilkS")
		)
		(fp_line
			(start 1.700022 0.899922)
			(end 1.700022 -0.899922)
			(stroke
				(width 0.1)
				(type default)
			)
			(layer "B.Fab")
		)
		(fp_line
			(start 1.700022 -0.899922)
			(end -1.700022 -0.899922)
			(stroke
				(width 0.1)
				(type default)
			)
			(layer "B.Fab")
		)
		(fp_line
			(start -1.700022 0.899922)
			(end 1.700022 0.899922)
			(stroke
				(width 0.1)
				(type default)
			)
			(layer "B.Fab")
		)
		(fp_line
			(start -1.700022 -0.899922)
			(end -1.700022 0.899922)
			(stroke
				(width 0.1)
				(type default)
			)
			(layer "B.Fab")
		)
		(pad "1" smd rect
			(at 1.4732 0 180)
			(size 1.1684 1.5748)
			(layers "B.Cu" "B.Mask" "B.Paste")
			(net "P52V_FAN_7")
		)
		(pad "2" smd rect
			(at -1.4732 0 180)
			(size 1.1684 1.5748)
			(layers "B.Cu" "B.Mask" "B.Paste")
			(net "GND")
		)
	)
	(footprint ""
		(layer "B.Cu")
		(at 6.108954 -50.877724)
		(property "Reference" "C2108"
			(at 0 0 0)
			(layer "B.SilkS")
			(hide yes)
			(effects
				(font
					(size 1.27 1.27)
				)
				(justify mirror)
			)
		)
		(property "Value" ""
			(at 0 0 0)
			(layer "B.Fab")
			(effects
				(font
					(size 1.27 1.27)
				)
				(justify mirror)
			)
		)
		(duplicate_pad_numbers_are_jumpers no)
		(fp_line
			(start -2.2098 -0.9398)
			(end -2.2098 0.9398)
			(stroke
				(width 0.1524)
				(type default)
			)
			(layer "B.SilkS")
		)
		(fp_line
			(start -2.2098 0.9398)
			(end 2.2098 0.9398)
			(stroke
				(width 0.1524)
				(type default)
			)
			(layer "B.SilkS")
		)
		(fp_line
			(start 2.2098 -0.9398)
			(end -2.2098 -0.9398)
			(stroke
				(width 0.1524)
				(type default)
			)
			(layer "B.SilkS")
		)
		(fp_line
			(start 2.2098 0.9398)
			(end 2.2098 -0.9398)
			(stroke
				(width 0.1524)
				(type default)
			)
			(layer "B.SilkS")
		)
		(fp_line
			(start -1.700022 -0.899922)
			(end -1.700022 0.899922)
			(stroke
				(width 0.1)
				(type default)
			)
			(layer "B.Fab")
		)
		(fp_line
			(start -1.700022 0.899922)
			(end 1.700022 0.899922)
			(stroke
				(width 0.1)
				(type default)
			)
			(layer "B.Fab")
		)
		(fp_line
			(start 1.700022 -0.899922)
			(end -1.700022 -0.899922)
			(stroke
				(width 0.1)
				(type default)
			)
			(layer "B.Fab")
		)
		(fp_line
			(start 1.700022 0.899922)
			(end 1.700022 -0.899922)
			(stroke
				(width 0.1)
				(type default)
			)
			(layer "B.Fab")
		)
		(pad "1" smd rect
			(at 1.4732 0)
			(size 1.1684 1.5748)
			(layers "B.Cu" "B.Mask" "B.Paste")
			(net "P52V_FAN_4")
		)
		(pad "2" smd rect
			(at -1.4732 0)
			(size 1.1684 1.5748)
			(layers "B.Cu" "B.Mask" "B.Paste")
			(net "GND")
		)
	)
	(footprint ""
		(layer "B.Cu")
		(at 47.498 -73.971912 90)
		(property "Reference" "PR38"
			(at 0 0 90)
			(layer "B.SilkS")
			(hide yes)
			(effects
				(font
					(size 1.27 1.27)
				)
				(justify mirror)
			)
		)
		(property "Value" ""
			(at 0 0 90)
			(layer "B.Fab")
			(effects
				(font
					(size 1.27 1.27)
				)
				(justify mirror)
			)
		)
		(duplicate_pad_numbers_are_jumpers no)
		(fp_line
			(start 0.7874 -0.4064)
			(end -0.7874 -0.4064)
			(stroke
				(width 0.1524)
				(type default)
			)
			(layer "B.SilkS")
		)
		(fp_line
			(start -0.7874 -0.4064)
			(end -0.7874 0.4064)
			(stroke
				(width 0.1524)
				(type default)
			)
			(layer "B.SilkS")
		)
		(fp_line
			(start 0.7874 0.4064)
			(end 0.7874 -0.4064)
			(stroke
				(width 0.1524)
				(type default)
			)
			(layer "B.SilkS")
		)
		(fp_line
			(start -0.7874 0.4064)
			(end 0.7874 0.4064)
			(stroke
				(width 0.1524)
				(type default)
			)
			(layer "B.SilkS")
		)
		(fp_line
			(start 0.67945 -0.305054)
			(end 0.12065 -0.305054)
			(stroke
				(width 0.1)
				(type default)
			)
			(layer "B.Fab")
		)
		(fp_line
			(start 0.12065 -0.305054)
			(end 0.12065 -0.2794)
			(stroke
				(width 0.1)
				(type default)
			)
			(layer "B.Fab")
		)
		(fp_line
			(start -0.12065 -0.3048)
			(end -0.67945 -0.3048)
			(stroke
				(width 0.1)
				(type default)
			)
			(layer "B.Fab")
		)
		(fp_line
			(start -0.67945 -0.3048)
			(end -0.67945 0.3048)
			(stroke
				(width 0.1)
				(type default)
			)
			(layer "B.Fab")
		)
		(fp_line
			(start 0.12065 -0.2794)
			(end -0.12065 -0.2794)
			(stroke
				(width 0.1)
				(type default)
			)
			(layer "B.Fab")
		)
		(fp_line
			(start -0.12065 -0.2794)
			(end -0.12065 -0.3048)
			(stroke
				(width 0.1)
				(type default)
			)
			(layer "B.Fab")
		)
		(fp_line
			(start 0.12065 0.2794)
			(end 0.12065 0.3048)
			(stroke
				(width 0.1)
				(type default)
			)
			(layer "B.Fab")
		)
		(fp_line
			(start -0.120396 0.2794)
			(end 0.12065 0.2794)
			(stroke
				(width 0.1)
				(type default)
			)
			(layer "B.Fab")
		)
		(fp_line
			(start 0.67945 0.3048)
			(end 0.67945 -0.305054)
			(stroke
				(width 0.1)
				(type default)
			)
			(layer "B.Fab")
		)
		(fp_line
			(start 0.12065 0.3048)
			(end 0.67945 0.3048)
			(stroke
				(width 0.1)
				(type default)
			)
			(layer "B.Fab")
		)
		(fp_line
			(start -0.120396 0.3048)
			(end -0.120396 0.2794)
			(stroke
				(width 0.1)
				(type default)
			)
			(layer "B.Fab")
		)
		(fp_line
			(start -0.67945 0.3048)
			(end -0.120396 0.3048)
			(stroke
				(width 0.1)
				(type default)
			)
			(layer "B.Fab")
		)
		(pad "1" smd circle
			(at 0.40005 0 270)
			(size 0 0)
			(layers "B.Cu" "B.Mask" "B.Paste")
			(net "FAN_2_CS")
		)
		(pad "2" smd circle
			(at -0.40005 0 270)
			(size 0 0)
			(layers "B.Cu" "B.Mask" "B.Paste")
			(net "GND")
		)
	)
)
